(kicad_pcb
	(version 20221018)
	(generator pcbnew)
	(general
    (thickness 1.62)
  )
	(paper "A4")
	(title_block
    (title "ECP5 - Datacenter Secure Control Module (DC-SCM)")
    (date "2024-07-01")
    (rev "1.2.1")
		(comment 9 "footprint 50 of 506 (U21), pads 1-100 of 756")
	)
	(layers
    (0 "F.Cu" signal)
    (1 "In1.Cu" power)
    (2 "In2.Cu" signal)
    (3 "In3.Cu" power)
    (4 "In4.Cu" power)
    (5 "In5.Cu" signal)
    (6 "In6.Cu" power)
    (31 "B.Cu" signal)
    (32 "B.Adhes" user "B.Adhesive")
    (33 "F.Adhes" user "F.Adhesive")
    (34 "B.Paste" user)
    (35 "F.Paste" user)
    (36 "B.SilkS" user "B.Silkscreen")
    (37 "F.SilkS" user "F.Silkscreen")
    (38 "B.Mask" user)
    (39 "F.Mask" user)
    (40 "Dwgs.User" user "User.Drawings")
    (41 "Cmts.User" user "User.Comments")
    (42 "Eco1.User" user "User.Eco1")
    (43 "Eco2.User" user "User.Eco2")
    (44 "Edge.Cuts" user)
    (45 "Margin" user)
    (46 "B.CrtYd" user "B.Courtyard")
    (47 "F.CrtYd" user "F.Courtyard")
    (48 "B.Fab" user)
    (49 "F.Fab" user)
  )
	(footprint "antmicro-footprints:BGA-1024-756_27x27mm_Layout32x32_P0.8mm" locked
    (layer "F.Cu")
    (at 104.4 120.55)
    (property "Author" "Antmicro")
    (property "License" "Apache-2.0")
    (property "MPN" "LFE5UM5G-85F-8BG756C")
    (property "Manufacturer" "Lattice Semiconductor")
    (property "Sheetfile" "fpga-power-supply.kicad_sch")
    (property "Sheetname" "FPGA power supply")
    (property "ki_description" "ECP5-5G Field Programmable Gate Array")
    (property "ki_keywords" "SMT, FPGA, IC")
    (attr smd)
    (fp_text reference "U21" (at -12.97 -14.53) (layer "F.SilkS")
        (effects (font (size 0.7 0.7) (thickness 0.127)))
    )
    (fp_text value "ECP5UM5G_85_CABGA756" (at 0 14.5) (layer "F.Fab")
        (effects (font (size 1 1) (thickness 0.15)))
    )
    (pad "A2" smd circle locked (at -11.6 -12.4) (size 0.4 0.4) (layers "F.Cu" "F.Paste" "F.Mask")
      (net 410 "PIRQ#") (pinfunction "PT6A") (pintype "bidirectional"))
    (pad "A3" smd circle locked (at -10.8 -12.4) (size 0.4 0.4) (layers "F.Cu" "F.Paste" "F.Mask")
      (net 411 "RST") (pinfunction "PT6B") (pintype "bidirectional"))
    (pad "A4" smd circle locked (at -10 -12.4) (size 0.4 0.4) (layers "F.Cu" "F.Paste" "F.Mask")
      (net 412 "GPIO") (pinfunction "PT9A") (pintype "bidirectional"))
    (pad "A5" smd circle locked (at -9.2 -12.4) (size 0.4 0.4) (layers "F.Cu" "F.Paste" "F.Mask")
      (net 413 "PP") (pinfunction "PT9B") (pintype "bidirectional"))
    (pad "A7" smd circle locked (at -7.6 -12.4) (size 0.4 0.4) (layers "F.Cu" "F.Paste" "F.Mask")
      (net 547 "unconnected-(U21B-PT13B-PadA7)") (pinfunction "PT13B") (pintype "bidirectional+no_connect"))
    (pad "A8" smd circle locked (at -6.8 -12.4) (size 0.4 0.4) (layers "F.Cu" "F.Paste" "F.Mask")
      (net 198 "RGMII_TXD1") (pinfunction "PT20B") (pintype "bidirectional"))
    (pad "A9" smd circle locked (at -6 -12.4) (size 0.4 0.4) (layers "F.Cu" "F.Paste" "F.Mask")
      (net 548 "unconnected-(U21B-PT24B-PadA9)") (pinfunction "PT24B") (pintype "bidirectional+no_connect"))
    (pad "A10" smd circle locked (at -5.2 -12.4) (size 0.4 0.4) (layers "F.Cu" "F.Paste" "F.Mask")
      (net 549 "unconnected-(U21B-PT31B-PadA10)") (pinfunction "PT31B") (pintype "bidirectional+no_connect"))
    (pad "A11" smd circle locked (at -4.4 -12.4) (size 0.4 0.4) (layers "F.Cu" "F.Paste" "F.Mask")
      (net 550 "unconnected-(U21B-PT38B-PadA11)") (pinfunction "PT38B") (pintype "bidirectional+no_connect"))
    (pad "A13" smd circle locked (at -2.8 -12.4) (size 0.4 0.4) (layers "F.Cu" "F.Paste" "F.Mask")
      (net 551 "unconnected-(U21B-PT42B-PadA13)") (pinfunction "PT42B") (pintype "bidirectional+no_connect"))
    (pad "A14" smd circle locked (at -2 -12.4) (size 0.4 0.4) (layers "F.Cu" "F.Paste" "F.Mask")
      (net 202 "RGMII_TXD0") (pinfunction "PT49B") (pintype "bidirectional"))
    (pad "A15" smd circle locked (at -1.2 -12.4) (size 0.4 0.4) (layers "F.Cu" "F.Paste" "F.Mask")
      (net 552 "unconnected-(U21B-PT54B-PadA15)") (pinfunction "PT54B") (pintype "bidirectional+no_connect"))
    (pad "A16" smd circle locked (at -0.4 -12.4) (size 0.4 0.4) (layers "F.Cu" "F.Paste" "F.Mask")
      (net 154 "RGMII_RXD0") (pinfunction "PT60B") (pintype "bidirectional"))
    (pad "A17" smd circle locked (at 0.4 -12.4) (size 0.4 0.4) (layers "F.Cu" "F.Paste" "F.Mask")
      (net 159 "RGMII_RX_CLK") (pinfunction "PT63A") (pintype "bidirectional"))
    (pad "A18" smd circle locked (at 1.2 -12.4) (size 0.4 0.4) (layers "F.Cu" "F.Paste" "F.Mask")
      (net 553 "unconnected-(U21C-PT71A-PadA18)") (pinfunction "PT71A") (pintype "bidirectional+no_connect"))
    (pad "A19" smd circle locked (at 2 -12.4) (size 0.4 0.4) (layers "F.Cu" "F.Paste" "F.Mask")
      (net 197 "ETH_INT_N") (pinfunction "PT76A") (pintype "bidirectional"))
    (pad "A20" smd circle locked (at 2.8 -12.4) (size 0.4 0.4) (layers "F.Cu" "F.Paste" "F.Mask")
      (net 168 "I3C[0]_SCL_3V3") (pinfunction "PT83A") (pintype "bidirectional"))
    (pad "A22" smd circle locked (at 4.4 -12.4) (size 0.4 0.4) (layers "F.Cu" "F.Paste" "F.Mask")
      (net 295 "USR_LED2") (pinfunction "PT87A") (pintype "bidirectional"))
    (pad "A23" smd circle locked (at 5.2 -12.4) (size 0.4 0.4) (layers "F.Cu" "F.Paste" "F.Mask")
      (net 49 "I2C[12]_SDA") (pinfunction "PT94A") (pintype "bidirectional"))
    (pad "A24" smd circle locked (at 6 -12.4) (size 0.4 0.4) (layers "F.Cu" "F.Paste" "F.Mask")
      (net 50 "I2C[12]_SCL") (pinfunction "PT101A") (pintype "bidirectional"))
    (pad "A25" smd circle locked (at 6.8 -12.4) (size 0.4 0.4) (layers "F.Cu" "F.Paste" "F.Mask")
      (net 42 "I2C[11]_SDA") (pinfunction "PT105A") (pintype "bidirectional"))
    (pad "A26" smd circle locked (at 7.6 -12.4) (size 0.4 0.4) (layers "F.Cu" "F.Paste" "F.Mask")
      (net 40 "I2C[11]_SCL") (pinfunction "PT112A") (pintype "bidirectional"))
    (pad "A28" smd circle locked (at 9.2 -12.4) (size 0.4 0.4) (layers "F.Cu" "F.Paste" "F.Mask")
      (net 26 "I2C[7]_SCL") (pinfunction "PT116A") (pintype "bidirectional"))
    (pad "A29" smd circle locked (at 10 -12.4) (size 0.4 0.4) (layers "F.Cu" "F.Paste" "F.Mask")
      (net 35 "I2C[6]_SDA") (pinfunction "PT116B") (pintype "bidirectional"))
    (pad "A30" smd circle locked (at 10.8 -12.4) (size 0.4 0.4) (layers "F.Cu" "F.Paste" "F.Mask")
      (net 34 "I2C[6]_SCL") (pinfunction "PT119A") (pintype "bidirectional"))
    (pad "A31" smd circle locked (at 11.6 -12.4) (size 0.4 0.4) (layers "F.Cu" "F.Paste" "F.Mask")
      (net 24 "I2C[5]_SCL") (pinfunction "PT119B") (pintype "bidirectional"))
    (pad "AA10" smd circle locked (at -5.2 3.6) (size 0.4 0.4) (layers "F.Cu" "F.Paste" "F.Mask")
      (net 3 "VCC1V35") (pinfunction "VCCIO6") (pintype "power_in"))
    (pad "AA11" smd circle locked (at -4.4 3.6) (size 0.4 0.4) (layers "F.Cu" "F.Paste" "F.Mask")
      (net 1 "GND") (pinfunction "GND") (pintype "power_in"))
    (pad "AA12" smd circle locked (at -3.6 3.6) (size 0.4 0.4) (layers "F.Cu" "F.Paste" "F.Mask")
      (net 211 "VCC1V2") (pinfunction "VCC") (pintype "power_in"))
    (pad "AA13" smd circle locked (at -2.8 3.6) (size 0.4 0.4) (layers "F.Cu" "F.Paste" "F.Mask")
      (net 211 "VCC1V2") (pinfunction "VCC") (pintype "passive"))
    (pad "AA14" smd circle locked (at -2 3.6) (size 0.4 0.4) (layers "F.Cu" "F.Paste" "F.Mask")
      (net 211 "VCC1V2") (pinfunction "VCC") (pintype "passive"))
    (pad "AA15" smd circle locked (at -1.2 3.6) (size 0.4 0.4) (layers "F.Cu" "F.Paste" "F.Mask")
      (net 211 "VCC1V2") (pinfunction "VCC") (pintype "passive"))
    (pad "AA16" smd circle locked (at -0.4 3.6) (size 0.4 0.4) (layers "F.Cu" "F.Paste" "F.Mask")
      (net 211 "VCC1V2") (pinfunction "VCC") (pintype "passive"))
    (pad "AA17" smd circle locked (at 0.4 3.6) (size 0.4 0.4) (layers "F.Cu" "F.Paste" "F.Mask")
      (net 211 "VCC1V2") (pinfunction "VCC") (pintype "passive"))
    (pad "AA18" smd circle locked (at 1.2 3.6) (size 0.4 0.4) (layers "F.Cu" "F.Paste" "F.Mask")
      (net 211 "VCC1V2") (pinfunction "VCC") (pintype "passive"))
    (pad "AA19" smd circle locked (at 2 3.6) (size 0.4 0.4) (layers "F.Cu" "F.Paste" "F.Mask")
      (net 211 "VCC1V2") (pinfunction "VCC") (pintype "passive"))
    (pad "AA20" smd circle locked (at 2.8 3.6) (size 0.4 0.4) (layers "F.Cu" "F.Paste" "F.Mask")
      (net 211 "VCC1V2") (pinfunction "VCC") (pintype "passive"))
    (pad "AA21" smd circle locked (at 3.6 3.6) (size 0.4 0.4) (layers "F.Cu" "F.Paste" "F.Mask")
      (net 211 "VCC1V2") (pinfunction "VCC") (pintype "passive"))
    (pad "AA22" smd circle locked (at 4.4 3.6) (size 0.4 0.4) (layers "F.Cu" "F.Paste" "F.Mask")
      (net 1 "GND") (pinfunction "GND") (pintype "passive"))
    (pad "AA23" smd circle locked (at 5.2 3.6) (size 0.4 0.4) (layers "F.Cu" "F.Paste" "F.Mask")
      (net 2 "VCC3V3") (pinfunction "VCCIO3") (pintype "power_in"))
    (pad "AB1" smd circle locked (at -12.4 4.4) (size 0.4 0.4) (layers "F.Cu" "F.Paste" "F.Mask")
      (net 187 "DDR3_DQ11") (pinfunction "PL92A") (pintype "bidirectional"))
    (pad "AB2" smd circle locked (at -11.6 4.4) (size 0.4 0.4) (layers "F.Cu" "F.Paste" "F.Mask")
      (net 176 "DDR3_DQS1-") (pinfunction "PL89B") (pintype "bidirectional"))
    (pad "AB3" smd circle locked (at -10.8 4.4) (size 0.4 0.4) (layers "F.Cu" "F.Paste" "F.Mask")
      (net 258 "DDR3_RAS") (pinfunction "PL83A") (pintype "bidirectional"))
    (pad "AB4" smd circle locked (at -10 4.4) (size 0.4 0.4) (layers "F.Cu" "F.Paste" "F.Mask")
      (net 185 "DDR3_DQ12") (pinfunction "PL83B") (pintype "bidirectional"))
    (pad "AB5" smd circle locked (at -9.2 4.4) (size 0.4 0.4) (layers "F.Cu" "F.Paste" "F.Mask")
      (net 183 "DDR3_DQS0+") (pinfunction "PL77A") (pintype "bidirectional"))
    (pad "AB6" smd circle locked (at -8.4 4.4) (size 0.4 0.4) (layers "F.Cu" "F.Paste" "F.Mask")
      (net 177 "DDR3_DQS0-") (pinfunction "PL77B") (pintype "bidirectional"))
    (pad "AB7" smd circle locked (at -7.6 4.4) (size 0.4 0.4) (layers "F.Cu" "F.Paste" "F.Mask")
      (net 192 "DDR3_DQ4") (pinfunction "PL74C") (pintype "bidirectional"))
    (pad "AB10" smd circle locked (at -5.2 4.4) (size 0.4 0.4) (layers "F.Cu" "F.Paste" "F.Mask")
      (net 2 "VCC3V3") (pinfunction "VCCIO8") (pintype "power_in"))
    (pad "AB11" smd circle locked (at -4.4 4.4) (size 0.4 0.4) (layers "F.Cu" "F.Paste" "F.Mask")
      (net 1 "GND") (pinfunction "GND") (pintype "passive"))
    (pad "AB12" smd circle locked (at -3.6 4.4) (size 0.4 0.4) (layers "F.Cu" "F.Paste" "F.Mask")
      (net 1 "GND") (pinfunction "GND") (pintype "passive"))
    (pad "AB13" smd circle locked (at -2.8 4.4) (size 0.4 0.4) (layers "F.Cu" "F.Paste" "F.Mask")
      (net 1 "GND") (pinfunction "GND") (pintype "passive"))
    (pad "AB14" smd circle locked (at -2 4.4) (size 0.4 0.4) (layers "F.Cu" "F.Paste" "F.Mask")
      (net 1 "GND") (pinfunction "GND") (pintype "passive"))
    (pad "AB15" smd circle locked (at -1.2 4.4) (size 0.4 0.4) (layers "F.Cu" "F.Paste" "F.Mask")
      (net 1 "GND") (pinfunction "GND") (pintype "passive"))
    (pad "AB16" smd circle locked (at -0.4 4.4) (size 0.4 0.4) (layers "F.Cu" "F.Paste" "F.Mask")
      (net 1 "GND") (pinfunction "GND") (pintype "passive"))
    (pad "AB17" smd circle locked (at 0.4 4.4) (size 0.4 0.4) (layers "F.Cu" "F.Paste" "F.Mask")
      (net 1 "GND") (pinfunction "GND") (pintype "passive"))
    (pad "AB18" smd circle locked (at 1.2 4.4) (size 0.4 0.4) (layers "F.Cu" "F.Paste" "F.Mask")
      (net 1 "GND") (pinfunction "GND") (pintype "passive"))
    (pad "AB19" smd circle locked (at 2 4.4) (size 0.4 0.4) (layers "F.Cu" "F.Paste" "F.Mask")
      (net 1 "GND") (pinfunction "GND") (pintype "passive"))
    (pad "AB20" smd circle locked (at 2.8 4.4) (size 0.4 0.4) (layers "F.Cu" "F.Paste" "F.Mask")
      (net 1 "GND") (pinfunction "GND") (pintype "passive"))
    (pad "AB21" smd circle locked (at 3.6 4.4) (size 0.4 0.4) (layers "F.Cu" "F.Paste" "F.Mask")
      (net 1 "GND") (pinfunction "GND") (pintype "passive"))
    (pad "AB22" smd circle locked (at 4.4 4.4) (size 0.4 0.4) (layers "F.Cu" "F.Paste" "F.Mask")
      (net 1 "GND") (pinfunction "GND") (pintype "passive"))
    (pad "AB23" smd circle locked (at 5.2 4.4) (size 0.4 0.4) (layers "F.Cu" "F.Paste" "F.Mask")
      (net 2 "VCC3V3") (pinfunction "VCCIO4") (pintype "power_in"))
    (pad "AB26" smd circle locked (at 7.6 4.4) (size 0.4 0.4) (layers "F.Cu" "F.Paste" "F.Mask")
      (net 554 "unconnected-(U21E-PR74C-PadAB26)") (pinfunction "PR74C") (pintype "bidirectional+no_connect"))
    (pad "AB27" smd circle locked (at 8.4 4.4) (size 0.4 0.4) (layers "F.Cu" "F.Paste" "F.Mask")
      (net 109 "HPM_FW_RECOVERY") (pinfunction "PR77B") (pintype "bidirectional"))
    (pad "AB28" smd circle locked (at 9.2 4.4) (size 0.4 0.4) (layers "F.Cu" "F.Paste" "F.Mask")
      (net 110 "HPM_STBY_RDY") (pinfunction "PR77A") (pintype "bidirectional"))
    (pad "AB29" smd circle locked (at 10 4.4) (size 0.4 0.4) (layers "F.Cu" "F.Paste" "F.Mask")
      (net 111 "HPM_STBY_EN") (pinfunction "PR83B") (pintype "bidirectional"))
    (pad "AB30" smd circle locked (at 10.8 4.4) (size 0.4 0.4) (layers "F.Cu" "F.Paste" "F.Mask")
      (net 322 "ULPI2_D7") (pinfunction "PR83A") (pintype "bidirectional"))
    (pad "AB31" smd circle locked (at 11.6 4.4) (size 0.4 0.4) (layers "F.Cu" "F.Paste" "F.Mask")
      (net 324 "ULPI2_D5") (pinfunction "PR89B") (pintype "bidirectional"))
    (pad "AB32" smd circle locked (at 12.4 4.4) (size 0.4 0.4) (layers "F.Cu" "F.Paste" "F.Mask")
      (net 323 "ULPI2_D6") (pinfunction "PR92A") (pintype "bidirectional"))
    (pad "AC1" smd circle locked (at -12.4 5.2) (size 0.4 0.4) (layers "F.Cu" "F.Paste" "F.Mask")
      (net 180 "DDR3_DQ13") (pinfunction "PL92B") (pintype "bidirectional"))
    (pad "AC2" smd circle locked (at -11.6 5.2) (size 0.4 0.4) (layers "F.Cu" "F.Paste" "F.Mask")
      (net 184 "DDR3_DM1") (pinfunction "PL89C") (pintype "bidirectional"))
    (pad "AC3" smd circle locked (at -10.8 5.2) (size 0.4 0.4) (layers "F.Cu" "F.Paste" "F.Mask")
      (net 175 "DDR3_DQS1+") (pinfunction "PL89A") (pintype "bidirectional"))
    (pad "AC4" smd circle locked (at -10 5.2) (size 0.4 0.4) (layers "F.Cu" "F.Paste" "F.Mask")
      (net 555 "unconnected-(U21A-NC-PadAC4)") (pinfunction "NC") (pintype "no_connect"))
    (pad "AC5" smd circle locked (at -9.2 5.2) (size 0.4 0.4) (layers "F.Cu" "F.Paste" "F.Mask")
      (net 251 "DDR3_WE") (pinfunction "PL83C") (pintype "bidirectional"))
    (pad "AC6" smd circle locked (at -8.4 5.2) (size 0.4 0.4) (layers "F.Cu" "F.Paste" "F.Mask")
      (net 196 "DDR3_DQ0") (pinfunction "PL74D") (pintype "bidirectional"))
    (pad "AC7" smd circle locked (at -7.6 5.2) (size 0.4 0.4) (layers "F.Cu" "F.Paste" "F.Mask")
      (net 256 "DDR3_BA0") (pinfunction "PL77C") (pintype "bidirectional"))
    (pad "AC10" smd circle locked (at -5.2 5.2) (size 0.4 0.4) (layers "F.Cu" "F.Paste" "F.Mask")
      (net 2 "VCC3V3") (pinfunction "VCCIO8") (pintype "passive"))
    (pad "AC11" smd circle locked (at -4.4 5.2) (size 0.4 0.4) (layers "F.Cu" "F.Paste" "F.Mask")
      (net 304 "/FPGA power supply/VCCAUX") (pinfunction "VCCAUX") (pintype "power_in"))
    (pad "AC12" smd circle locked (at -3.6 5.2) (size 0.4 0.4) (layers "F.Cu" "F.Paste" "F.Mask")
      (net 1 "GND") (pinfunction "GND") (pintype "passive"))
    (pad "AC13" smd circle locked (at -2.8 5.2) (size 0.4 0.4) (layers "F.Cu" "F.Paste" "F.Mask")
      (net 5 "/FPGA power supply/VCCHTX0") (pinfunction "VCCHTX0_D0CH0") (pintype "power_in"))
    (pad "AC14" smd circle locked (at -2 5.2) (size 0.4 0.4) (layers "F.Cu" "F.Paste" "F.Mask")
      (net 302 "/FPGA power supply/VCCA0") (pinfunction "VCCHRX0_D0CH0") (pintype "power_in"))
    (pad "AC15" smd circle locked (at -1.2 5.2) (size 0.4 0.4) (layers "F.Cu" "F.Paste" "F.Mask")
      (net 303 "/FPGA power supply/VCCA1") (pinfunction "VCCHRX1_D0CH1") (pintype "power_in"))
    (pad "AC16" smd circle locked (at -0.4 5.2) (size 0.4 0.4) (layers "F.Cu" "F.Paste" "F.Mask")
      (net 6 "/FPGA power supply/VCCHTX1") (pinfunction "VCCHTX1_D0CH1") (pintype "power_in"))
    (pad "AC17" smd circle locked (at 0.4 5.2) (size 0.4 0.4) (layers "F.Cu" "F.Paste" "F.Mask")
      (net 5 "/FPGA power supply/VCCHTX0") (pinfunction "VCCHTX0_D1CH0") (pintype "power_in"))
    (pad "AC18" smd circle locked (at 1.2 5.2) (size 0.4 0.4) (layers "F.Cu" "F.Paste" "F.Mask")
      (net 302 "/FPGA power supply/VCCA0") (pinfunction "VCCHRX0_D1CH0") (pintype "power_in"))
    (pad "AC19" smd circle locked (at 2 5.2) (size 0.4 0.4) (layers "F.Cu" "F.Paste" "F.Mask")
      (net 303 "/FPGA power supply/VCCA1") (pinfunction "VCCHRX1_D1CH1") (pintype "power_in"))
    (pad "AC20" smd circle locked (at 2.8 5.2) (size 0.4 0.4) (layers "F.Cu" "F.Paste" "F.Mask")
      (net 6 "/FPGA power supply/VCCHTX1") (pinfunction "VCCHTX1_D1CH1") (pintype "power_in"))
    (pad "AC21" smd circle locked (at 3.6 5.2) (size 0.4 0.4) (layers "F.Cu" "F.Paste" "F.Mask")
      (net 1 "GND") (pinfunction "GND") (pintype "passive"))
    (pad "AC22" smd circle locked (at 4.4 5.2) (size 0.4 0.4) (layers "F.Cu" "F.Paste" "F.Mask")
      (net 304 "/FPGA power supply/VCCAUX") (pinfunction "VCCAUX") (pintype "passive"))
    (pad "AC23" smd circle locked (at 5.2 5.2) (size 0.4 0.4) (layers "F.Cu" "F.Paste" "F.Mask")
      (net 2 "VCC3V3") (pinfunction "VCCIO4") (pintype "passive"))
    (pad "AC26" smd circle locked (at 7.6 5.2) (size 0.4 0.4) (layers "F.Cu" "F.Paste" "F.Mask")
      (net 556 "unconnected-(U21E-PR77C-PadAC26)") (pinfunction "PR77C") (pintype "bidirectional+no_connect"))
    (pad "AC27" smd circle locked (at 8.4 5.2) (size 0.4 0.4) (layers "F.Cu" "F.Paste" "F.Mask")
      (net 557 "unconnected-(U21E-PR74D-PadAC27)") (pinfunction "PR74D") (pintype "bidirectional+no_connect"))
    (pad "AC28" smd circle locked (at 9.2 5.2) (size 0.4 0.4) (layers "F.Cu" "F.Paste" "F.Mask")
      (net 558 "unconnected-(U21E-PR83C-PadAC28)") (pinfunction "PR83C") (pintype "bidirectional+no_connect"))
    (pad "AC29" smd circle locked (at 10 5.2) (size 0.4 0.4) (layers "F.Cu" "F.Paste" "F.Mask")
      (net 559 "unconnected-(U21A-NC-PadAC29)") (pinfunction "NC") (pintype "no_connect"))
    (pad "AC30" smd circle locked (at 10.8 5.2) (size 0.4 0.4) (layers "F.Cu" "F.Paste" "F.Mask")
      (net 560 "unconnected-(U21E-PR89A-PadAC30)") (pinfunction "PR89A") (pintype "bidirectional+no_connect"))
    (pad "AC31" smd circle locked (at 11.6 5.2) (size 0.4 0.4) (layers "F.Cu" "F.Paste" "F.Mask")
      (net 326 "ULPI2_D3") (pinfunction "PR89C") (pintype "bidirectional"))
    (pad "AC32" smd circle locked (at 12.4 5.2) (size 0.4 0.4) (layers "F.Cu" "F.Paste" "F.Mask")
      (net 325 "ULPI2_D4") (pinfunction "PR92B") (pintype "bidirectional"))
    (pad "AD1" smd circle locked (at -12.4 6) (size 0.4 0.4) (layers "F.Cu" "F.Paste" "F.Mask")
      (net 179 "DDR3_DQ15") (pinfunction "PL92C") (pintype "bidirectional"))
    (pad "AD2" smd circle locked (at -11.6 6) (size 0.4 0.4) (layers "F.Cu" "F.Paste" "F.Mask")
      (net 1 "GND") (pinfunction "GND") (pintype "passive"))
    (pad "AD3" smd circle locked (at -10.8 6) (size 0.4 0.4) (layers "F.Cu" "F.Paste" "F.Mask")
      (net 186 "DDR3_DQ10") (pinfunction "PL86C") (pintype "bidirectional"))
    (pad "AD4" smd circle locked (at -10 6) (size 0.4 0.4) (layers "F.Cu" "F.Paste" "F.Mask")
      (net 259 "DDR3_ODT") (pinfunction "PL83D") (pintype "bidirectional"))
  )
)
